# T6G (Grand Teton) — schematic netlist excerpt (pin names and nets, part order shuffled) for the footprints in the layout excerpt that follows; sources: Cadence DE-HDL packaged netlist, KiCad conversion of 04192023_DAF0TMB3IC0_F0TG_MB_C_brd_V02_OCP.brd

R1132  Q_RES  0 5% CHIP  pkg 0402LF  page 136 : A = P12V_OCP_V3_1_PLD_R_PWRGD ; B = P12V_OCP_V3_1_PLD_PWRGD
R3974  Q_RES  0 5% EMPTY  pkg 0402LF  page 146 : A = P12V_E1S_SENSE_0 ; B = P12V_E1S_0_ISENSE_MAM_MAM

(kicad_pcb
	(version 20260206)
	(generator "pcbnew")
	(generator_version "10.0")
	(general
		(thickness 1.6)
		(legacy_teardrops no)
	)
	(paper "A4")
	(title_block
		(title "04192023_DAF0TMB3IC0_F0TG_MB_C_brd_V02_OCP.brd")
		(comment 1 "Grand Teton / footprints 1861-1862 of 8354")
	)
	(layers
		(0 "F.Cu" signal "TOP")
		(4 "In1.Cu" signal "GND")
		(6 "In2.Cu" signal "IN1")
		(8 "In3.Cu" signal "GND1")
		(10 "In4.Cu" signal "IN2")
		(12 "In5.Cu" signal "GND2")
		(14 "In6.Cu" signal "IN3")
		(16 "In7.Cu" signal "GND3")
		(18 "In8.Cu" signal "VCC")
		(20 "In9.Cu" signal "VCC1")
		(22 "In10.Cu" signal "GND4")
		(24 "In11.Cu" signal "IN4")
		(26 "In12.Cu" signal "GND5")
		(28 "In13.Cu" signal "IN5")
		(30 "In14.Cu" signal "GND6")
		(32 "In15.Cu" signal "IN6")
		(34 "In16.Cu" signal "GND7")
		(2 "B.Cu" signal "BOTTOM")
		(9 "F.Adhes" user "F.Adhesive")
		(11 "B.Adhes" user "B.Adhesive")
		(13 "F.Paste" user "Package Geometry/Pastemask Top")
		(15 "B.Paste" user "Package Geometry/Pastemask Bottom")
		(5 "F.SilkS" user "Ref Des/Silkscreen Top")
		(7 "B.SilkS" user "Ref Des/Silkscreen Bottom")
		(1 "F.Mask" user "Board Geometry/Soldermask Top")
		(3 "B.Mask" user "Board Geometry/Soldermask Bottom")
		(17 "Dwgs.User" user "User.Drawings")
		(19 "Cmts.User" user "User.Comments")
		(21 "Eco1.User" user "User.Eco1")
		(23 "Eco2.User" user "User.Eco2")
		(25 "Edge.Cuts" user "Board Geometry/Outline")
		(27 "Margin" user)
		(31 "F.CrtYd" user "Package Geometry/Place Bound Top")
		(29 "B.CrtYd" user "Package Geometry/Place Bound Bottom")
		(35 "F.Fab" user "Ref Des/Assembly Top")
		(33 "B.Fab" user "Ref Des/Assembly Bottom")
	)
	(footprint ""
		(layer "F.Cu")
		(at 204.994764 -95.695262)
		(property "Reference" "R1132"
			(at 0 0 0)
			(layer "F.SilkS")
			(hide yes)
			(effects
				(font
					(size 1.27 1.27)
				)
			)
		)
		(property "Value" ""
			(at 0 0 0)
			(layer "F.Fab")
			(effects
				(font
					(size 1.27 1.27)
				)
			)
		)
		(duplicate_pad_numbers_are_jumpers no)
		(fp_line
			(start -0.7874 -0.4064)
			(end 0.7874 -0.4064)
			(stroke
				(width 0.1524)
				(type default)
			)
			(layer "F.SilkS")
		)
		(fp_line
			(start -0.7874 0.4064)
			(end -0.7874 -0.4064)
			(stroke
				(width 0.1524)
				(type default)
			)
			(layer "F.SilkS")
		)
		(fp_line
			(start 0.7874 -0.4064)
			(end 0.7874 0.4064)
			(stroke
				(width 0.1524)
				(type default)
			)
			(layer "F.SilkS")
		)
		(fp_line
			(start 0.7874 0.4064)
			(end -0.7874 0.4064)
			(stroke
				(width 0.1524)
				(type default)
			)
			(layer "F.SilkS")
		)
		(fp_line
			(start -0.67945 -0.305054)
			(end -0.12065 -0.305054)
			(stroke
				(width 0.1)
				(type default)
			)
			(layer "F.Fab")
		)
		(fp_line
			(start -0.67945 0.3048)
			(end -0.67945 -0.305054)
			(stroke
				(width 0.1)
				(type default)
			)
			(layer "F.Fab")
		)
		(fp_line
			(start -0.12065 -0.305054)
			(end -0.12065 -0.2794)
			(stroke
				(width 0.1)
				(type default)
			)
			(layer "F.Fab")
		)
		(fp_line
			(start -0.12065 -0.2794)
			(end 0.12065 -0.2794)
			(stroke
				(width 0.1)
				(type default)
			)
			(layer "F.Fab")
		)
		(fp_line
			(start -0.12065 0.2794)
			(end -0.12065 0.3048)
			(stroke
				(width 0.1)
				(type default)
			)
			(layer "F.Fab")
		)
		(fp_line
			(start -0.12065 0.3048)
			(end -0.67945 0.3048)
			(stroke
				(width 0.1)
				(type default)
			)
			(layer "F.Fab")
		)
		(fp_line
			(start 0.120396 0.2794)
			(end -0.12065 0.2794)
			(stroke
				(width 0.1)
				(type default)
			)
			(layer "F.Fab")
		)
		(fp_line
			(start 0.120396 0.3048)
			(end 0.120396 0.2794)
			(stroke
				(width 0.1)
				(type default)
			)
			(layer "F.Fab")
		)
		(fp_line
			(start 0.12065 -0.3048)
			(end 0.67945 -0.3048)
			(stroke
				(width 0.1)
				(type default)
			)
			(layer "F.Fab")
		)
		(fp_line
			(start 0.12065 -0.2794)
			(end 0.12065 -0.3048)
			(stroke
				(width 0.1)
				(type default)
			)
			(layer "F.Fab")
		)
		(fp_line
			(start 0.67945 -0.3048)
			(end 0.67945 0.3048)
			(stroke
				(width 0.1)
				(type default)
			)
			(layer "F.Fab")
		)
		(fp_line
			(start 0.67945 0.3048)
			(end 0.120396 0.3048)
			(stroke
				(width 0.1)
				(type default)
			)
			(layer "F.Fab")
		)
		(pad "1" smd circle
			(at -0.40005 0)
			(size 0 0)
			(layers "F.Cu" "F.Mask" "F.Paste")
			(net "P12V_OCP_V3_1_PLD_R_PWRGD")
		)
		(pad "2" smd circle
			(at 0.40005 0)
			(size 0 0)
			(layers "F.Cu" "F.Mask" "F.Paste")
			(net "P12V_OCP_V3_1_PLD_PWRGD")
		)
	)
	(footprint ""
		(layer "F.Cu")
		(at 257.85953 -58.527442 180)
		(property "Reference" "R3974"
			(at 0 0 180)
			(layer "F.SilkS")
			(hide yes)
			(effects
				(font
					(size 1.27 1.27)
				)
			)
		)
		(property "Value" ""
			(at 0 0 180)
			(layer "F.Fab")
			(effects
				(font
					(size 1.27 1.27)
				)
			)
		)
		(duplicate_pad_numbers_are_jumpers no)
		(fp_line
			(start 0.7874 0.4064)
			(end -0.7874 0.4064)
			(stroke
				(width 0.1524)
				(type default)
			)
			(layer "F.SilkS")
		)
		(fp_line
			(start 0.7874 -0.4064)
			(end 0.7874 0.4064)
			(stroke
				(width 0.1524)
				(type default)
			)
			(layer "F.SilkS")
		)
		(fp_line
			(start -0.7874 0.4064)
			(end -0.7874 -0.4064)
			(stroke
				(width 0.1524)
				(type default)
			)
			(layer "F.SilkS")
		)
		(fp_line
			(start -0.7874 -0.4064)
			(end 0.7874 -0.4064)
			(stroke
				(width 0.1524)
				(type default)
			)
			(layer "F.SilkS")
		)
		(fp_line
			(start 0.67945 0.3048)
			(end 0.120396 0.3048)
			(stroke
				(width 0.1)
				(type default)
			)
			(layer "F.Fab")
		)
		(fp_line
			(start 0.67945 -0.3048)
			(end 0.67945 0.3048)
			(stroke
				(width 0.1)
				(type default)
			)
			(layer "F.Fab")
		)
		(fp_line
			(start 0.12065 -0.2794)
			(end 0.12065 -0.3048)
			(stroke
				(width 0.1)
				(type default)
			)
			(layer "F.Fab")
		)
		(fp_line
			(start 0.12065 -0.3048)
			(end 0.67945 -0.3048)
			(stroke
				(width 0.1)
				(type default)
			)
			(layer "F.Fab")
		)
		(fp_line
			(start 0.120396 0.3048)
			(end 0.120396 0.2794)
			(stroke
				(width 0.1)
				(type default)
			)
			(layer "F.Fab")
		)
		(fp_line
			(start 0.120396 0.2794)
			(end -0.12065 0.2794)
			(stroke
				(width 0.1)
				(type default)
			)
			(layer "F.Fab")
		)
		(fp_line
			(start -0.12065 0.3048)
			(end -0.67945 0.3048)
			(stroke
				(width 0.1)
				(type default)
			)
			(layer "F.Fab")
		)
		(fp_line
			(start -0.12065 0.2794)
			(end -0.12065 0.3048)
			(stroke
				(width 0.1)
				(type default)
			)
			(layer "F.Fab")
		)
		(fp_line
			(start -0.12065 -0.2794)
			(end 0.12065 -0.2794)
			(stroke
				(width 0.1)
				(type default)
			)
			(layer "F.Fab")
		)
		(fp_line
			(start -0.12065 -0.305054)
			(end -0.12065 -0.2794)
			(stroke
				(width 0.1)
				(type default)
			)
			(layer "F.Fab")
		)
		(fp_line
			(start -0.67945 0.3048)
			(end -0.67945 -0.305054)
			(stroke
				(width 0.1)
				(type default)
			)
			(layer "F.Fab")
		)
		(fp_line
			(start -0.67945 -0.305054)
			(end -0.12065 -0.305054)
			(stroke
				(width 0.1)
				(type default)
			)
			(layer "F.Fab")
		)
		(pad "1" smd rect
			(at -0.40005 0)
			(size 0.4572 0.508)
			(layers "F.Cu" "F.Mask" "F.Paste")
			(net "P12V_E1S_SENSE_0")
		)
		(pad "2" smd rect
			(at 0.40005 0)
			(size 0.4572 0.508)
			(layers "F.Cu" "F.Mask" "F.Paste")
			(net "P12V_E1S_0_ISENSE_MAM_MAM")
		)
	)
)
